(kicad_pcb
	(version 20260206)
	(generator "pcbnew")
	(generator_version "10.0")
	(general
		(thickness 1.6)
		(legacy_teardrops no)
	)
	(paper "A4")
	(title_block
		(title "Bryce Canyon_IOM_IOC_16318-2_OCP.brd")
		(comment 1 "Bryce Canyon / footprints 934-941 of 1605")
	)
	(layers
		(0 "F.Cu" signal "TOP")
		(4 "In1.Cu" signal "L2GND")
		(6 "In2.Cu" signal "L3")
		(8 "In3.Cu" signal "L4VCC")
		(10 "In4.Cu" signal "L5VCC")
		(12 "In5.Cu" signal "L6")
		(14 "In6.Cu" signal "L7GND")
		(2 "B.Cu" signal "BOTTOM")
		(9 "F.Adhes" user "F.Adhesive")
		(11 "B.Adhes" user "B.Adhesive")
		(13 "F.Paste" user "Package Geometry/Pastemask Top")
		(15 "B.Paste" user "Package Geometry/Pastemask Bottom")
		(5 "F.SilkS" user "Ref Des/Silkscreen Top")
		(7 "B.SilkS" user "Ref Des/Silkscreen Bottom")
		(1 "F.Mask" user "Board Geometry/Soldermask Top")
		(3 "B.Mask" user "Board Geometry/Soldermask Bottom")
		(17 "Dwgs.User" user "User.Drawings")
		(19 "Cmts.User" user "User.Comments")
		(21 "Eco1.User" user "User.Eco1")
		(23 "Eco2.User" user "User.Eco2")
		(25 "Edge.Cuts" user "Board Geometry/Outline")
		(27 "Margin" user)
		(31 "F.CrtYd" user "Package Geometry/Place Bound Top")
		(29 "B.CrtYd" user "Package Geometry/Place Bound Bottom")
		(35 "F.Fab" user "Ref Des/Assembly Top")
		(33 "B.Fab" user "Ref Des/Assembly Bottom")
	)
	(footprint ""
		(layer "F.Cu")
		(at 208.055972 -74.4728 90)
		(property "Reference" "C310"
			(at 0 0 90)
			(layer "F.SilkS")
			(hide yes)
			(effects
				(font
					(size 1.27 1.27)
				)
			)
		)
		(property "Value" "SCD01U16V1KX-GP"
			(at -2.8321 -1.7399 90)
			(unlocked yes)
			(layer "F.Fab")
			(hide yes)
			(effects
				(font
					(size 1.016 1.016)
					(thickness 0.1524)
				)
			)
		)
		(property "Device Type" "C0201H13"
			(at -2.8321 -3.2639 90)
			(unlocked yes)
			(layer "F.Fab")
			(hide yes)
			(effects
				(font
					(size 1.016 1.016)
					(thickness 0.1524)
				)
			)
		)
		(duplicate_pad_numbers_are_jumpers no)
		(fp_rect
			(start -0.2794 0.6477)
			(end 0.2794 -0.6477)
			(stroke
				(width 0)
				(type default)
			)
			(fill no)
			(layer "F.CrtYd")
		)
		(fp_rect
			(start -0.2794 0.6477)
			(end 0.2794 -0.6477)
			(stroke
				(width 0)
				(type default)
			)
			(fill no)
			(layer "F.Fab")
		)
		(pad "1" smd custom
			(at 0 -0.2794 90)
			(size 0.0762 0.0762)
			(layers "F.Cu" "F.Mask" "F.Paste")
			(net "PHY_IOC_TO_CON_A_1_DN_C")
			(options
				(clearance outline)
				(anchor circle)
			)
			(primitives
				(gr_poly
					(pts
						(arc
							(start 0.1524 -0.127)
							(mid 0.137521 -0.162921)
							(end 0.1016 -0.1778)
						)
						(arc
							(start -0.1016 -0.1778)
							(mid -0.137521 -0.162921)
							(end -0.1524 -0.127)
						)
						(arc
							(start -0.1524 0.127)
							(mid -0.137521 0.162921)
							(end -0.1016 0.1778)
						)
						(arc
							(start 0.1016 0.1778)
							(mid 0.137521 0.162921)
							(end 0.1524 0.127)
						)
					)
					(width 0)
					(fill yes)
				)
			)
		)
		(pad "2" smd custom
			(at 0 0.2794 90)
			(size 0.0762 0.0762)
			(layers "F.Cu" "F.Mask" "F.Paste")
			(net "PHY_IOC_TO_CON_A_1_DN")
			(options
				(clearance outline)
				(anchor circle)
			)
			(primitives
				(gr_poly
					(pts
						(arc
							(start 0.1524 -0.127)
							(mid 0.137521 -0.162921)
							(end 0.1016 -0.1778)
						)
						(arc
							(start -0.1016 -0.1778)
							(mid -0.137521 -0.162921)
							(end -0.1524 -0.127)
						)
						(arc
							(start -0.1524 0.127)
							(mid -0.137521 0.162921)
							(end -0.1016 0.1778)
						)
						(arc
							(start 0.1016 0.1778)
							(mid 0.137521 0.162921)
							(end 0.1524 0.127)
						)
					)
					(width 0)
					(fill yes)
				)
			)
		)
	)
	(footprint ""
		(layer "F.Cu")
		(at 27.99588 -122.859292)
		(property "Reference" "R85"
			(at 0 0 0)
			(layer "F.SilkS")
			(hide yes)
			(effects
				(font
					(size 1.27 1.27)
				)
			)
		)
		(property "Value" "100KR2F-L1-GP"
			(at 0.064008 -3.993896 0)
			(unlocked yes)
			(layer "F.Fab")
			(hide yes)
			(effects
				(font
					(size 1.016 1.016)
					(thickness 0.1524)
				)
			)
		)
		(property "Device Type" "R402H16"
			(at 0.064008 -5.517896 0)
			(unlocked yes)
			(layer "F.Fab")
			(hide yes)
			(effects
				(font
					(size 1.016 1.016)
					(thickness 0.1524)
				)
			)
		)
		(duplicate_pad_numbers_are_jumpers no)
		(fp_line
			(start -0.508 -0.9398)
			(end -0.508 0.9398)
			(stroke
				(width 0.1524)
				(type default)
			)
			(layer "F.SilkS")
		)
		(fp_line
			(start 0.508 -0.9398)
			(end -0.508 -0.9398)
			(stroke
				(width 0.1524)
				(type default)
			)
			(layer "F.SilkS")
		)
		(fp_rect
			(start -0.508 0.9398)
			(end 0.508 -0.9398)
			(stroke
				(width 0)
				(type default)
			)
			(fill no)
			(layer "F.CrtYd")
		)
		(fp_rect
			(start -0.508 0.9398)
			(end 0.508 -0.9398)
			(stroke
				(width 0)
				(type default)
			)
			(fill no)
			(layer "F.Fab")
		)
		(pad "1" smd custom
			(at 0 -0.4445)
			(size 0.1397 0.1397)
			(layers "F.Cu" "F.Mask" "F.Paste")
			(net "WP_ENABLE")
			(options
				(clearance outline)
				(anchor circle)
			)
			(primitives
				(gr_poly
					(pts
						(arc
							(start -0.1778 -0.2794)
							(mid -0.249642 -0.249642)
							(end -0.2794 -0.1778)
						)
						(arc
							(start -0.2794 0.1778)
							(mid -0.249642 0.249642)
							(end -0.1778 0.2794)
						)
						(arc
							(start 0.1778 0.2794)
							(mid 0.249642 0.249642)
							(end 0.2794 0.1778)
						)
						(arc
							(start 0.2794 -0.1778)
							(mid 0.249642 -0.249642)
							(end 0.1778 -0.2794)
						)
					)
					(width 0)
					(fill yes)
				)
			)
		)
		(pad "2" smd custom
			(at 0 0.4445)
			(size 0.1397 0.1397)
			(layers "F.Cu" "F.Mask" "F.Paste")
			(net "GND")
			(options
				(clearance outline)
				(anchor circle)
			)
			(primitives
				(gr_poly
					(pts
						(arc
							(start -0.1778 -0.2794)
							(mid -0.249642 -0.249642)
							(end -0.2794 -0.1778)
						)
						(arc
							(start -0.2794 0.1778)
							(mid -0.249642 0.249642)
							(end -0.1778 0.2794)
						)
						(arc
							(start 0.1778 0.2794)
							(mid 0.249642 0.249642)
							(end 0.2794 0.1778)
						)
						(arc
							(start 0.2794 -0.1778)
							(mid 0.249642 -0.249642)
							(end 0.1778 -0.2794)
						)
					)
					(width 0)
					(fill yes)
				)
			)
		)
	)
	(footprint ""
		(layer "F.Cu")
		(at 222.499936 -187.999878)
		(property "Reference" ""
			(at 0 0 0)
			(layer "F.SilkS")
			(hide yes)
			(effects
				(font
					(size 1.27 1.27)
				)
			)
		)
		(property "Value" "*"
			(at -6.38175 0.19685 0)
			(unlocked yes)
			(layer "F.Fab")
			(hide yes)
			(effects
				(font
					(size 1.016 1.016)
					(thickness 0.1524)
				)
			)
		)
		(duplicate_pad_numbers_are_jumpers no)
		(fp_poly
			(pts
				(arc
					(start 5.0673 0)
					(mid -5.0673 0)
					(end 5.0673 0)
				)
			)
			(stroke
				(width 0)
				(type default)
			)
			(fill no)
			(layer "B.CrtYd")
		)
		(fp_poly
			(pts
				(arc
					(start 5.0673 0)
					(mid -5.0673 0)
					(end 5.0673 0)
				)
			)
			(stroke
				(width 0)
				(type default)
			)
			(fill no)
			(layer "F.CrtYd")
		)
		(fp_poly
			(pts
				(arc
					(start 5.0673 0)
					(mid -5.0673 0)
					(end 5.0673 0)
				)
			)
			(stroke
				(width 0)
				(type default)
			)
			(fill no)
			(layer "B.Fab")
		)
		(fp_poly
			(pts
				(arc
					(start 5.0673 0)
					(mid -5.0673 0)
					(end 5.0673 0)
				)
			)
			(stroke
				(width 0)
				(type default)
			)
			(fill no)
			(layer "F.Fab")
		)
		(pad "1" thru_hole circle
			(at 0 0)
			(size 9.525 9.525)
			(drill 3.5052)
			(layers "*.Cu" "*.Mask")
			(remove_unused_layers no)
			(net "Net_14")
			(clearance -2.5019)
			(thermal_gap 0.3048)
			(padstack
				(mode front_inner_back)
				(layer "Inner"
					(shape circle)
					(size 3.9116 3.9116)
					(clearance 0.3048)
				)
				(layer "B.Cu"
					(shape circle)
					(size 9.525 9.525)
					(clearance -2.5019)
				)
			)
		)
	)
	(footprint ""
		(layer "F.Cu")
		(at 47.8536 -164.0078 180)
		(property "Reference" "R367"
			(at 0 0 180)
			(layer "F.SilkS")
			(hide yes)
			(effects
				(font
					(size 1.27 1.27)
				)
			)
		)
		(property "Value" "18KR2F-5-GP"
			(at 0.064008 -3.993896 180)
			(unlocked yes)
			(layer "F.Fab")
			(hide yes)
			(effects
				(font
					(size 1.016 1.016)
					(thickness 0.1524)
				)
			)
		)
		(property "Device Type" "R402H16"
			(at 0.064008 -5.517896 180)
			(unlocked yes)
			(layer "F.Fab")
			(hide yes)
			(effects
				(font
					(size 1.016 1.016)
					(thickness 0.1524)
				)
			)
		)
		(duplicate_pad_numbers_are_jumpers no)
		(fp_line
			(start 0.508 -0.9398)
			(end -0.508 -0.9398)
			(stroke
				(width 0.1524)
				(type default)
			)
			(layer "F.SilkS")
		)
		(fp_line
			(start -0.508 -0.9398)
			(end -0.508 0.9398)
			(stroke
				(width 0.1524)
				(type default)
			)
			(layer "F.SilkS")
		)
		(fp_rect
			(start -0.508 0.9398)
			(end 0.508 -0.9398)
			(stroke
				(width 0)
				(type default)
			)
			(fill no)
			(layer "F.CrtYd")
		)
		(fp_rect
			(start -0.508 0.9398)
			(end 0.508 -0.9398)
			(stroke
				(width 0)
				(type default)
			)
			(fill no)
			(layer "F.Fab")
		)
		(pad "1" smd custom
			(at 0 -0.4445 180)
			(size 0.1397 0.1397)
			(layers "F.Cu" "F.Mask" "F.Paste")
			(net "GND")
			(options
				(clearance outline)
				(anchor circle)
			)
			(primitives
				(gr_poly
					(pts
						(arc
							(start -0.1778 -0.2794)
							(mid -0.249642 -0.249642)
							(end -0.2794 -0.1778)
						)
						(arc
							(start -0.2794 0.1778)
							(mid -0.249642 0.249642)
							(end -0.1778 0.2794)
						)
						(arc
							(start 0.1778 0.2794)
							(mid 0.249642 0.249642)
							(end 0.2794 0.1778)
						)
						(arc
							(start 0.2794 -0.1778)
							(mid 0.249642 -0.249642)
							(end 0.1778 -0.2794)
						)
					)
					(width 0)
					(fill yes)
				)
			)
		)
		(pad "2" smd custom
			(at 0 0.4445 180)
			(size 0.1397 0.1397)
			(layers "F.Cu" "F.Mask" "F.Paste")
			(net "DACRSET")
			(options
				(clearance outline)
				(anchor circle)
			)
			(primitives
				(gr_poly
					(pts
						(arc
							(start -0.1778 -0.2794)
							(mid -0.249642 -0.249642)
							(end -0.2794 -0.1778)
						)
						(arc
							(start -0.2794 0.1778)
							(mid -0.249642 0.249642)
							(end -0.1778 0.2794)
						)
						(arc
							(start 0.1778 0.2794)
							(mid 0.249642 0.249642)
							(end 0.2794 0.1778)
						)
						(arc
							(start 0.2794 -0.1778)
							(mid 0.249642 -0.249642)
							(end 0.1778 -0.2794)
						)
					)
					(width 0)
					(fill yes)
				)
			)
		)
	)
	(footprint ""
		(layer "F.Cu")
		(at 197.4088 -126.619)
		(property "Reference" "R565"
			(at 0 0 0)
			(layer "F.SilkS")
			(hide yes)
			(effects
				(font
					(size 1.27 1.27)
				)
			)
		)
		(property "Value" "221R2F-2-GP"
			(at 0.064008 -3.993896 0)
			(unlocked yes)
			(layer "F.Fab")
			(hide yes)
			(effects
				(font
					(size 1.016 1.016)
					(thickness 0.1524)
				)
			)
		)
		(property "Device Type" "R402H16"
			(at 0.064008 -5.517896 0)
			(unlocked yes)
			(layer "F.Fab")
			(hide yes)
			(effects
				(font
					(size 1.016 1.016)
					(thickness 0.1524)
				)
			)
		)
		(duplicate_pad_numbers_are_jumpers no)
		(fp_line
			(start -0.508 -0.9398)
			(end -0.508 0.9398)
			(stroke
				(width 0.1524)
				(type default)
			)
			(layer "F.SilkS")
		)
		(fp_line
			(start 0.508 -0.9398)
			(end -0.508 -0.9398)
			(stroke
				(width 0.1524)
				(type default)
			)
			(layer "F.SilkS")
		)
		(fp_rect
			(start -0.508 0.9398)
			(end 0.508 -0.9398)
			(stroke
				(width 0)
				(type default)
			)
			(fill no)
			(layer "F.CrtYd")
		)
		(fp_rect
			(start -0.508 0.9398)
			(end 0.508 -0.9398)
			(stroke
				(width 0)
				(type default)
			)
			(fill no)
			(layer "F.Fab")
		)
		(pad "1" smd custom
			(at 0 -0.4445)
			(size 0.1397 0.1397)
			(layers "F.Cu" "F.Mask" "F.Paste")
			(net "VT235_VDES_RCC")
			(options
				(clearance outline)
				(anchor circle)
			)
			(primitives
				(gr_poly
					(pts
						(arc
							(start -0.1778 -0.2794)
							(mid -0.249642 -0.249642)
							(end -0.2794 -0.1778)
						)
						(arc
							(start -0.2794 0.1778)
							(mid -0.249642 0.249642)
							(end -0.1778 0.2794)
						)
						(arc
							(start 0.1778 0.2794)
							(mid 0.249642 0.249642)
							(end 0.2794 0.1778)
						)
						(arc
							(start 0.2794 -0.1778)
							(mid 0.249642 -0.249642)
							(end 0.1778 -0.2794)
						)
					)
					(width 0)
					(fill yes)
				)
			)
		)
		(pad "2" smd custom
			(at 0 0.4445)
			(size 0.1397 0.1397)
			(layers "F.Cu" "F.Mask" "F.Paste")
			(net "GND_SEN")
			(options
				(clearance outline)
				(anchor circle)
			)
			(primitives
				(gr_poly
					(pts
						(arc
							(start -0.1778 -0.2794)
							(mid -0.249642 -0.249642)
							(end -0.2794 -0.1778)
						)
						(arc
							(start -0.2794 0.1778)
							(mid -0.249642 0.249642)
							(end -0.1778 0.2794)
						)
						(arc
							(start 0.1778 0.2794)
							(mid 0.249642 0.249642)
							(end 0.2794 0.1778)
						)
						(arc
							(start 0.2794 -0.1778)
							(mid 0.249642 -0.249642)
							(end 0.1778 -0.2794)
						)
					)
					(width 0)
					(fill yes)
				)
			)
		)
	)
	(footprint ""
		(layer "F.Cu")
		(at 45.99559 -158.1912)
		(property "Reference" "R172"
			(at 0 0 0)
			(layer "F.SilkS")
			(hide yes)
			(effects
				(font
					(size 1.27 1.27)
				)
			)
		)
		(property "Value" "0R2J-2-GP"
			(at 0.064008 -3.993896 0)
			(unlocked yes)
			(layer "F.Fab")
			(hide yes)
			(effects
				(font
					(size 1.016 1.016)
					(thickness 0.1524)
				)
			)
		)
		(property "Device Type" "R402H16"
			(at 0.064008 -5.517896 0)
			(unlocked yes)
			(layer "F.Fab")
			(hide yes)
			(effects
				(font
					(size 1.016 1.016)
					(thickness 0.1524)
				)
			)
		)
		(duplicate_pad_numbers_are_jumpers no)
		(fp_line
			(start -0.508 -0.9398)
			(end -0.508 0.9398)
			(stroke
				(width 0.1524)
				(type default)
			)
			(layer "F.SilkS")
		)
		(fp_line
			(start 0.508 -0.9398)
			(end -0.508 -0.9398)
			(stroke
				(width 0.1524)
				(type default)
			)
			(layer "F.SilkS")
		)
		(fp_rect
			(start -0.508 0.9398)
			(end 0.508 -0.9398)
			(stroke
				(width 0)
				(type default)
			)
			(fill no)
			(layer "F.CrtYd")
		)
		(fp_rect
			(start -0.508 0.9398)
			(end 0.508 -0.9398)
			(stroke
				(width 0)
				(type default)
			)
			(fill no)
			(layer "F.Fab")
		)
		(pad "1" smd custom
			(at 0 -0.4445)
			(size 0.1397 0.1397)
			(layers "F.Cu" "F.Mask" "F.Paste")
			(net "I2C_DPB_SDA_OUT")
			(options
				(clearance outline)
				(anchor circle)
			)
			(primitives
				(gr_poly
					(pts
						(arc
							(start -0.1778 -0.2794)
							(mid -0.249642 -0.249642)
							(end -0.2794 -0.1778)
						)
						(arc
							(start -0.2794 0.1778)
							(mid -0.249642 0.249642)
							(end -0.1778 0.2794)
						)
						(arc
							(start 0.1778 0.2794)
							(mid 0.249642 0.249642)
							(end 0.2794 0.1778)
						)
						(arc
							(start 0.2794 -0.1778)
							(mid 0.249642 -0.249642)
							(end 0.1778 -0.2794)
						)
					)
					(width 0)
					(fill yes)
				)
			)
		)
		(pad "2" smd custom
			(at 0 0.4445)
			(size 0.1397 0.1397)
			(layers "F.Cu" "F.Mask" "F.Paste")
			(net "BMC_SMB7_DAT")
			(options
				(clearance outline)
				(anchor circle)
			)
			(primitives
				(gr_poly
					(pts
						(arc
							(start -0.1778 -0.2794)
							(mid -0.249642 -0.249642)
							(end -0.2794 -0.1778)
						)
						(arc
							(start -0.2794 0.1778)
							(mid -0.249642 0.249642)
							(end -0.1778 0.2794)
						)
						(arc
							(start 0.1778 0.2794)
							(mid 0.249642 0.249642)
							(end 0.2794 0.1778)
						)
						(arc
							(start 0.2794 -0.1778)
							(mid 0.249642 -0.249642)
							(end 0.1778 -0.2794)
						)
					)
					(width 0)
					(fill yes)
				)
			)
		)
	)
	(footprint ""
		(layer "F.Cu")
		(at 191.242188 -49.984406)
		(property "Reference" "TP152"
			(at 0 0 0)
			(layer "F.SilkS")
			(hide yes)
			(effects
				(font
					(size 1.27 1.27)
				)
			)
		)
		(property "Value" "TPAD28-2-GP"
			(at -0.0127 -1.6637 0)
			(unlocked yes)
			(layer "F.Fab")
			(hide yes)
			(effects
				(font
					(size 1.016 1.016)
					(thickness 0.1524)
				)
			)
		)
		(property "Device Type" "TPAD28"
			(at -0.0127 -3.1877 0)
			(unlocked yes)
			(layer "F.Fab")
			(hide yes)
			(effects
				(font
					(size 1.016 1.016)
					(thickness 0.1524)
				)
			)
		)
		(duplicate_pad_numbers_are_jumpers no)
		(fp_poly
			(pts
				(arc
					(start 0.3556 0)
					(mid -0.3556 0)
					(end 0.3556 0)
				)
			)
			(stroke
				(width 0)
				(type default)
			)
			(fill no)
			(layer "F.CrtYd")
		)
		(fp_poly
			(pts
				(arc
					(start 0.6096 0)
					(mid -0.6096 0)
					(end 0.6096 0)
				)
			)
			(stroke
				(width 0)
				(type default)
			)
			(fill no)
			(layer "F.Fab")
		)
		(pad "1" smd circle
			(at 0 0)
			(size 0.7112 0.7112)
			(layers "F.Cu" "F.Mask" "F.Paste")
			(net "JTAG_IOC_TDI")
		)
	)
	(footprint ""
		(layer "F.Cu")
		(at 207.408018 -101.337872 -90)
		(property "Reference" "R606"
			(at 0 0 270)
			(layer "F.SilkS")
			(hide yes)
			(effects
				(font
					(size 1.27 1.27)
				)
			)
		)
		(property "Value" "0R2J-2-GP"
			(at 0.064008 -3.993896 270)
			(unlocked yes)
			(layer "F.Fab")
			(hide yes)
			(effects
				(font
					(size 1.016 1.016)
					(thickness 0.1524)
				)
			)
		)
		(property "Device Type" "R402H16"
			(at 0.064008 -5.517896 270)
			(unlocked yes)
			(layer "F.Fab")
			(hide yes)
			(effects
				(font
					(size 1.016 1.016)
					(thickness 0.1524)
				)
			)
		)
		(duplicate_pad_numbers_are_jumpers no)
		(fp_line
			(start -0.508 -0.9398)
			(end -0.508 0.9398)
			(stroke
				(width 0.1524)
				(type default)
			)
			(layer "F.SilkS")
		)
		(fp_line
			(start 0.508 -0.9398)
			(end -0.508 -0.9398)
			(stroke
				(width 0.1524)
				(type default)
			)
			(layer "F.SilkS")
		)
		(fp_rect
			(start -0.508 0.9398)
			(end 0.508 -0.9398)
			(stroke
				(width 0)
				(type default)
			)
			(fill no)
			(layer "F.CrtYd")
		)
		(fp_rect
			(start -0.508 0.9398)
			(end 0.508 -0.9398)
			(stroke
				(width 0)
				(type default)
			)
			(fill no)
			(layer "F.Fab")
		)
		(pad "1" smd custom
			(at 0 -0.4445 270)
			(size 0.1397 0.1397)
			(layers "F.Cu" "F.Mask" "F.Paste")
			(net "IOC_EEPROM_SCL")
			(options
				(clearance outline)
				(anchor circle)
			)
			(primitives
				(gr_poly
					(pts
						(arc
							(start -0.1778 -0.2794)
							(mid -0.249642 -0.249642)
							(end -0.2794 -0.1778)
						)
						(arc
							(start -0.2794 0.1778)
							(mid -0.249642 0.249642)
							(end -0.1778 0.2794)
						)
						(arc
							(start 0.1778 0.2794)
							(mid 0.249642 0.249642)
							(end 0.2794 0.1778)
						)
						(arc
							(start 0.2794 -0.1778)
							(mid 0.249642 -0.249642)
							(end 0.1778 -0.2794)
						)
					)
					(width 0)
					(fill yes)
				)
			)
		)
		(pad "2" smd custom
			(at 0 0.4445 270)
			(size 0.1397 0.1397)
			(layers "F.Cu" "F.Mask" "F.Paste")
			(net "SBL_SCL")
			(options
				(clearance outline)
				(anchor circle)
			)
			(primitives
				(gr_poly
					(pts
						(arc
							(start -0.1778 -0.2794)
							(mid -0.249642 -0.249642)
							(end -0.2794 -0.1778)
						)
						(arc
							(start -0.2794 0.1778)
							(mid -0.249642 0.249642)
							(end -0.1778 0.2794)
						)
						(arc
							(start 0.1778 0.2794)
							(mid 0.249642 0.249642)
							(end 0.2794 0.1778)
						)
						(arc
							(start 0.2794 -0.1778)
							(mid 0.249642 -0.249642)
							(end 0.1778 -0.2794)
						)
					)
					(width 0)
					(fill yes)
				)
			)
		)
	)
)
